# BASEBOARD_FAB2 (Tioga Pass) — schematic netlist excerpt (pin names and nets, part order shuffled) for the footprints in the layout excerpt that follows; sources: Cadence DE-HDL packaged netlist, KiCad conversion of Wiwynn_Tioga_Pass_MB.brd

R4P1  RES  240 1.0% EMPTY  pkg 0402  page 90 : A = GND ; B = PD_CPU0_BIST_ENABLE
C6L7  CAP_A  0.01UF 25V 10% X7R  pkg 0402V  page 98 : A = M_E_CPU_VREF ; B = GND
C3P38  CAP  0.22UF 16V 10% X7R  pkg 0402  page 107 : A = P3E_CPU0_PE1_SS_TXP<7> ; B = P3E_CPU0_PE1_SS_C_TXP<7>

(kicad_pcb
	(version 20260206)
	(generator "pcbnew")
	(generator_version "10.0")
	(general
		(thickness 1.6)
		(legacy_teardrops no)
	)
	(paper "A4")
	(title_block
		(title "Wiwynn_Tioga_Pass_MB.brd")
		(comment 1 "Tioga Pass / footprints 3007-3009 of 4770")
	)
	(layers
		(0 "F.Cu" signal "TOP")
		(4 "In1.Cu" signal "L2GND")
		(6 "In2.Cu" signal "L3")
		(8 "In3.Cu" signal "L4GND")
		(10 "In4.Cu" signal "L5")
		(12 "In5.Cu" signal "L6GND")
		(14 "In6.Cu" signal "L7VCC")
		(16 "In7.Cu" signal "L8VCC")
		(18 "In8.Cu" signal "L9GND")
		(20 "In9.Cu" signal "L10")
		(22 "In10.Cu" signal "L11GND")
		(24 "In11.Cu" signal "L12")
		(26 "In12.Cu" signal "L13GND")
		(2 "B.Cu" signal "BOTTOM")
		(9 "F.Adhes" user "F.Adhesive")
		(11 "B.Adhes" user "B.Adhesive")
		(13 "F.Paste" user "Package Geometry/Pastemask Top")
		(15 "B.Paste" user "Package Geometry/Pastemask Bottom")
		(5 "F.SilkS" user "Ref Des/Silkscreen Top")
		(7 "B.SilkS" user "Ref Des/Silkscreen Bottom")
		(1 "F.Mask" user "Board Geometry/Soldermask Top")
		(3 "B.Mask" user "Board Geometry/Soldermask Bottom")
		(17 "Dwgs.User" user "User.Drawings")
		(19 "Cmts.User" user "User.Comments")
		(21 "Eco1.User" user "User.Eco1")
		(23 "Eco2.User" user "User.Eco2")
		(25 "Edge.Cuts" user "Board Geometry/Outline")
		(27 "Margin" user)
		(31 "F.CrtYd" user "Package Geometry/Place Bound Top")
		(29 "B.CrtYd" user "Package Geometry/Place Bound Bottom")
		(35 "F.Fab" user "Ref Des/Assembly Top")
		(33 "B.Fab" user "Ref Des/Assembly Bottom")
	)
	(footprint ""
		(layer "B.Cu")
		(at 359.84688 -77.923136)
		(property "Reference" "C3P38"
			(at 0 0 0)
			(layer "B.SilkS")
			(hide yes)
			(effects
				(font
					(size 1.27 1.27)
				)
				(justify mirror)
			)
		)
		(property "Value" ""
			(at 0 0 0)
			(layer "B.Fab")
			(effects
				(font
					(size 1.27 1.27)
				)
				(justify mirror)
			)
		)
		(duplicate_pad_numbers_are_jumpers no)
		(fp_poly
			(pts
				(xy -0.3048 -0.1016) (xy -0.3048 0.9906) (xy 0.3048 0.9906) (xy 0.3048 -0.1016)
			)
			(stroke
				(width 0)
				(type default)
			)
			(fill no)
			(layer "B.CrtYd")
		)
		(fp_line
			(start -0.3048 -0.1016)
			(end 0.3048 -0.1016)
			(stroke
				(width 0.1)
				(type default)
			)
			(layer "B.Fab")
		)
		(fp_line
			(start -0.3048 0.9906)
			(end -0.3048 -0.1016)
			(stroke
				(width 0.1)
				(type default)
			)
			(layer "B.Fab")
		)
		(fp_line
			(start 0.3048 -0.1016)
			(end 0.3048 0.9906)
			(stroke
				(width 0.1)
				(type default)
			)
			(layer "B.Fab")
		)
		(fp_line
			(start 0.3048 0.9906)
			(end -0.3048 0.9906)
			(stroke
				(width 0.1)
				(type default)
			)
			(layer "B.Fab")
		)
		(pad "1" smd rect
			(at 0 0 180)
			(size 0.508 0.508)
			(layers "B.Cu" "B.Mask" "B.Paste")
			(net "P3E_CPU0_PE1_SS_TXP<7>")
		)
		(pad "2" smd rect
			(at 0 0.889 180)
			(size 0.508 0.508)
			(layers "B.Cu" "B.Mask" "B.Paste")
			(net "P3E_CPU0_PE1_SS_C_TXP<7>")
		)
		(zone
			(layer "B.Cu")
			(hatch none 0.5)
			(connect_pads
				(clearance 0)
			)
			(min_thickness 0.25)
			(keepout
				(tracks allowed)
				(vias not_allowed)
				(pads allowed)
				(copperpour not_allowed)
				(footprints allowed)
			)
			(placement
				(enabled no)
				(sheetname "")
			)
			(fill
				(thermal_gap 0.5)
				(thermal_bridge_width 0.5)
				(island_removal_mode 0)
			)
			(polygon
				(pts
					(xy 360.10088 -77.669136) (xy 359.59288 -77.669136) (xy 359.59288 -77.288136) (xy 360.10088 -77.288136)
				)
			)
		)
		(zone
			(layer "B.Cu")
			(hatch none 0.5)
			(connect_pads
				(clearance 0)
			)
			(min_thickness 0.25)
			(keepout
				(tracks not_allowed)
				(vias allowed)
				(pads allowed)
				(copperpour not_allowed)
				(footprints allowed)
			)
			(placement
				(enabled no)
				(sheetname "")
			)
			(fill
				(thermal_gap 0.5)
				(thermal_bridge_width 0.5)
				(island_removal_mode 0)
			)
			(polygon
				(pts
					(xy 360.10088 -77.288136) (xy 359.59288 -77.288136) (xy 359.59288 -77.669136) (xy 360.10088 -77.669136)
				)
			)
		)
	)
	(footprint ""
		(layer "B.Cu")
		(at 191.77 -144.4752 180)
		(property "Reference" "C6L7"
			(at 0 0 0)
			(layer "B.SilkS")
			(hide yes)
			(effects
				(font
					(size 1.27 1.27)
				)
				(justify mirror)
			)
		)
		(property "Value" ""
			(at 0 0 0)
			(layer "B.Fab")
			(effects
				(font
					(size 1.27 1.27)
				)
				(justify mirror)
			)
		)
		(duplicate_pad_numbers_are_jumpers no)
		(fp_poly
			(pts
				(xy -0.3048 -0.1016) (xy -0.3048 0.9906) (xy 0.3048 0.9906) (xy 0.3048 -0.1016)
			)
			(stroke
				(width 0)
				(type default)
			)
			(fill no)
			(layer "B.CrtYd")
		)
		(fp_line
			(start 0.3048 0.9906)
			(end -0.3048 0.9906)
			(stroke
				(width 0.1)
				(type default)
			)
			(layer "B.Fab")
		)
		(fp_line
			(start 0.3048 -0.1016)
			(end 0.3048 0.9906)
			(stroke
				(width 0.1)
				(type default)
			)
			(layer "B.Fab")
		)
		(fp_line
			(start -0.3048 0.9906)
			(end -0.3048 -0.1016)
			(stroke
				(width 0.1)
				(type default)
			)
			(layer "B.Fab")
		)
		(fp_line
			(start -0.3048 -0.1016)
			(end 0.3048 -0.1016)
			(stroke
				(width 0.1)
				(type default)
			)
			(layer "B.Fab")
		)
		(pad "1" smd rect
			(at 0 0)
			(size 0.508 0.508)
			(layers "B.Cu" "B.Mask" "B.Paste")
			(net "M_E_CPU_VREF")
		)
		(pad "2" smd rect
			(at 0 0.889)
			(size 0.508 0.508)
			(layers "B.Cu" "B.Mask" "B.Paste")
			(net "GND")
		)
		(zone
			(layer "B.Cu")
			(hatch none 0.5)
			(connect_pads
				(clearance 0)
			)
			(min_thickness 0.25)
			(keepout
				(tracks not_allowed)
				(vias allowed)
				(pads allowed)
				(copperpour not_allowed)
				(footprints allowed)
			)
			(placement
				(enabled no)
				(sheetname "")
			)
			(fill
				(thermal_gap 0.5)
				(thermal_bridge_width 0.5)
				(island_removal_mode 0)
			)
			(polygon
				(pts
					(xy 191.516 -145.1102) (xy 192.024 -145.1102) (xy 192.024 -144.7292) (xy 191.516 -144.7292)
				)
			)
		)
		(zone
			(layer "B.Cu")
			(hatch none 0.5)
			(connect_pads
				(clearance 0)
			)
			(min_thickness 0.25)
			(keepout
				(tracks allowed)
				(vias not_allowed)
				(pads allowed)
				(copperpour not_allowed)
				(footprints allowed)
			)
			(placement
				(enabled no)
				(sheetname "")
			)
			(fill
				(thermal_gap 0.5)
				(thermal_bridge_width 0.5)
				(island_removal_mode 0)
			)
			(polygon
				(pts
					(xy 191.516 -144.7292) (xy 192.024 -144.7292) (xy 192.024 -145.1102) (xy 191.516 -145.1102)
				)
			)
		)
	)
	(footprint ""
		(layer "B.Cu")
		(at 282.0162 -81.6102)
		(property "Reference" "R4P1"
			(at 0 0 0)
			(layer "B.SilkS")
			(hide yes)
			(effects
				(font
					(size 1.27 1.27)
				)
				(justify mirror)
			)
		)
		(property "Value" ""
			(at 0 0 0)
			(layer "B.Fab")
			(effects
				(font
					(size 1.27 1.27)
				)
				(justify mirror)
			)
		)
		(duplicate_pad_numbers_are_jumpers no)
		(fp_poly
			(pts
				(xy 0.2794 -0.1016) (xy -0.2794 -0.1016) (xy -0.2794 0.9906) (xy 0.2794 0.9906)
			)
			(stroke
				(width 0)
				(type default)
			)
			(fill no)
			(layer "B.CrtYd")
		)
		(fp_line
			(start -0.2794 -0.1016)
			(end 0.2794 -0.1016)
			(stroke
				(width 0.1)
				(type default)
			)
			(layer "B.Fab")
		)
		(fp_line
			(start -0.2794 0.9906)
			(end -0.2794 -0.1016)
			(stroke
				(width 0.1)
				(type default)
			)
			(layer "B.Fab")
		)
		(fp_line
			(start 0.2794 -0.1016)
			(end 0.2794 0.9906)
			(stroke
				(width 0.1)
				(type default)
			)
			(layer "B.Fab")
		)
		(fp_line
			(start 0.2794 0.9906)
			(end -0.2794 0.9906)
			(stroke
				(width 0.1)
				(type default)
			)
			(layer "B.Fab")
		)
		(pad "1" smd rect
			(at 0 0 180)
			(size 0.508 0.508)
			(layers "B.Cu" "B.Mask" "B.Paste")
			(net "GND")
		)
		(pad "2" smd rect
			(at 0 0.889 180)
			(size 0.508 0.508)
			(layers "B.Cu" "B.Mask" "B.Paste")
			(net "PD_CPU0_BIST_ENABLE")
		)
		(zone
			(layer "B.Cu")
			(hatch none 0.5)
			(connect_pads
				(clearance 0)
			)
			(min_thickness 0.25)
			(keepout
				(tracks allowed)
				(vias not_allowed)
				(pads allowed)
				(copperpour not_allowed)
				(footprints allowed)
			)
			(placement
				(enabled no)
				(sheetname "")
			)
			(fill
				(thermal_gap 0.5)
				(thermal_bridge_width 0.5)
				(island_removal_mode 0)
			)
			(polygon
				(pts
					(xy 282.2702 -81.3562) (xy 281.7622 -81.3562) (xy 281.7622 -80.9752) (xy 282.2702 -80.9752)
				)
			)
		)
		(zone
			(layer "B.Cu")
			(hatch none 0.5)
			(connect_pads
				(clearance 0)
			)
			(min_thickness 0.25)
			(keepout
				(tracks not_allowed)
				(vias allowed)
				(pads allowed)
				(copperpour not_allowed)
				(footprints allowed)
			)
			(placement
				(enabled no)
				(sheetname "")
			)
			(fill
				(thermal_gap 0.5)
				(thermal_bridge_width 0.5)
				(island_removal_mode 0)
			)
			(polygon
				(pts
					(xy 282.2702 -80.9752) (xy 281.7622 -80.9752) (xy 281.7622 -81.3562) (xy 282.2702 -81.3562)
				)
			)
		)
	)
)
